(kicad_pcb
	(version 20221018)
	(generator pcbnew)
	(general
    (thickness 1.562)
  )
	(paper "A4")
	(title_block
    (title "Thunderbolt PCIe Adaper")
    (date "2024-07-09")
    (rev "1.0.3")
    (comment 1 "www.antmicro.com")
    (comment 2 "Antmicro Ltd.")
		(comment 9 "footprints 124-132 of 271")
	)
	(layers
    (0 "F.Cu" signal)
    (1 "In1.Cu" signal)
    (2 "In2.Cu" signal)
    (3 "In3.Cu" signal)
    (4 "In4.Cu" signal)
    (31 "B.Cu" signal)
    (32 "B.Adhes" user "B.Adhesive")
    (33 "F.Adhes" user "F.Adhesive")
    (34 "B.Paste" user)
    (35 "F.Paste" user)
    (36 "B.SilkS" user "B.Silkscreen")
    (37 "F.SilkS" user "F.Silkscreen")
    (38 "B.Mask" user)
    (39 "F.Mask" user)
    (40 "Dwgs.User" user "User.Drawings")
    (41 "Cmts.User" user "User.Comments")
    (42 "Eco1.User" user "User.Eco1")
    (43 "Eco2.User" user "User.Eco2")
    (44 "Edge.Cuts" user)
    (45 "Margin" user)
    (46 "B.CrtYd" user "B.Courtyard")
    (47 "F.CrtYd" user "F.Courtyard")
    (48 "B.Fab" user)
    (49 "F.Fab" user)
  )
	(footprint "antmicro-footprints:Fiducial_1mm_Mask3mm" (layer "B.Cu")
    (at 108.7 52 180)
    (descr "Circular Fiducial, 1.5mm bare copper, 3mm soldermask opening")
    (tags "fiducial")
    (property "Author" "Antmicro")
    (property "License" "Apache-2.0")
    (property "Sheetfile" "thunderbolt-pcie-adapter.kicad_sch")
    (property "Sheetname" "")
    (property "exclude_from_bom" "")
    (property "ki_description" "Fiducial mask")
    (attr through_hole exclude_from_bom)
    (fp_text reference "FID6" (at -1.155 -2.61) (layer "B.SilkS")
        (effects (font (size 0.7 0.7) (thickness 0.15)) (justify left bottom mirror))
    )
    (fp_text value "Fiducial_1mm_Mask3mm" (at 0 -2.603) (layer "B.Fab")
        (effects (font (size 0.7 0.7) (thickness 0.15)) (justify left bottom mirror))
    )
    (fp_text user "License: Apache-2.0" (at -1.25 -7.003) (layer "B.Fab") hide
        (effects (font (size 0.7 0.7) (thickness 0.15)) (justify left bottom mirror))
    )
    (fp_text user "Author: Antmicro" (at -1.25 -5.803) (layer "B.Fab") hide
        (effects (font (size 0.7 0.7) (thickness 0.15)) (justify left bottom mirror))
    )
    (fp_text user "${REFERENCE}" (at -1.25 -4.603) (layer "B.Fab") hide
        (effects (font (size 0.7 0.7) (thickness 0.15)) (justify left bottom mirror))
    )
    (fp_circle (center 0 0) (end 1.5 0)
      (stroke (width 0.05) (type solid)) (fill none) (layer "B.CrtYd"))
    (fp_circle (center 0 0) (end 1.5 0)
      (stroke (width 0.15) (type solid)) (fill none) (layer "B.Fab"))
    (pad "" smd circle (at 0 0 180) (size 1 1) (layers "B.Cu" "B.Mask")
      (solder_mask_margin 1) (clearance 1))
  )
	(footprint "antmicro-footprints:R_0402_1005Metric" (layer "B.Cu")
    (at 137.225 68.77 90)
    (descr "Resistor SMD 0402")
    (tags "resistor SMD 0402")
    (property "Author" "Antmicro")
    (property "License" "Apache-2.0")
    (property "MPN" "CR0402-FX-1000GLF")
    (property "Manufacturer" "Bourns")
    (property "Sheetfile" "tb.kicad_sch")
    (property "Sheetname" "TB Controller")
    (property "Tolerance" "1%")
    (property "Val" "100R")
    (property "ki_description" "SMD Chip Resistor, 100 ohm, ± 1%, 62.5 mW, 0402 [1005 Metric], Thick Film, General Purpose")
    (property "ki_keywords" "0402, SMT, RESISTOR, PASSIVE")
    (attr smd)
    (fp_text reference "R88" (at 1.124 3.736 270) (layer "B.SilkS")
        (effects (font (size 0.7 0.7) (thickness 0.15)) (justify left bottom mirror))
    )
    (fp_text value "R_100R_0402" (at -1.011843 -1.772047 270) (layer "B.Fab")
        (effects (font (size 0.7 0.7) (thickness 0.15)) (justify left bottom mirror))
    )
    (fp_text user "Author: Antmicro" (at -0.95 -4.169 270) (layer "B.Fab") hide
        (effects (font (size 0.7 0.7) (thickness 0.15)) (justify left bottom mirror))
    )
    (fp_text user "License: Apache-2.0" (at -0.95 -5.169 270) (layer "B.Fab") hide
        (effects (font (size 0.7 0.7) (thickness 0.15)) (justify left bottom mirror))
    )
    (fp_text user "${REFERENCE}" (at -0.95 -3.168 270) (layer "B.Fab") hide
        (effects (font (size 0.7 0.7) (thickness 0.15)) (justify left bottom mirror))
    )
    (fp_rect (start -0.925 0.47) (end 0.925 -0.47)
      (stroke (width 0.05) (type default)) (fill none) (layer "B.CrtYd"))
    (fp_rect (start -0.5 0.25) (end 0.5 -0.25)
      (stroke (width 0.15) (type solid)) (fill none) (layer "B.Fab"))
    (pad "1" smd roundrect (at -0.48 0 90) (size 0.59 0.64) (layers "B.Cu" "B.Paste" "B.Mask") (roundrect_rratio 0.25)
      (net 203 "Net-(U4D-TEST_EN)") (pintype "passive"))
    (pad "2" smd roundrect (at 0.48 0 90) (size 0.59 0.64) (layers "B.Cu" "B.Paste" "B.Mask") (roundrect_rratio 0.25)
      (net 1 "GND") (pintype "passive"))
  )
	(footprint "antmicro-footprints:R_0402_1005Metric" (layer "B.Cu")
    (at 136.2 68.77 90)
    (descr "Resistor SMD 0402")
    (tags "resistor SMD 0402")
    (property "Author" "Antmicro")
    (property "License" "Apache-2.0")
    (property "MPN" "CR0402-FX-1003GLF")
    (property "Manufacturer" "Bourns")
    (property "Sheetfile" "tb.kicad_sch")
    (property "Sheetname" "TB Controller")
    (property "Tolerance" "1%")
    (property "Val" "100k")
    (property "ki_description" "SMD Chip Resistor, 100 kohm, ± 1%, 62.5 mW, 0402 [1005 Metric], Thick Film, General Purpose")
    (property "ki_keywords" "0402, SMT, RESISTOR, PASSIVE")
    (attr smd)
    (fp_text reference "R87" (at 1.124 3.736 270) (layer "B.SilkS")
        (effects (font (size 0.7 0.7) (thickness 0.15)) (justify left bottom mirror))
    )
    (fp_text value "R_100k_0402" (at -1.011843 -1.772047 270) (layer "B.Fab")
        (effects (font (size 0.7 0.7) (thickness 0.15)) (justify left bottom mirror))
    )
    (fp_text user "${REFERENCE}" (at -0.95 -3.168 270) (layer "B.Fab") hide
        (effects (font (size 0.7 0.7) (thickness 0.15)) (justify left bottom mirror))
    )
    (fp_text user "License: Apache-2.0" (at -0.95 -5.169 270) (layer "B.Fab") hide
        (effects (font (size 0.7 0.7) (thickness 0.15)) (justify left bottom mirror))
    )
    (fp_text user "Author: Antmicro" (at -0.95 -4.169 270) (layer "B.Fab") hide
        (effects (font (size 0.7 0.7) (thickness 0.15)) (justify left bottom mirror))
    )
    (fp_rect (start -0.925 0.47) (end 0.925 -0.47)
      (stroke (width 0.05) (type default)) (fill none) (layer "B.CrtYd"))
    (fp_rect (start -0.5 0.25) (end 0.5 -0.25)
      (stroke (width 0.15) (type solid)) (fill none) (layer "B.Fab"))
    (pad "1" smd roundrect (at -0.48 0 90) (size 0.59 0.64) (layers "B.Cu" "B.Paste" "B.Mask") (roundrect_rratio 0.25)
      (net 202 "Net-(U4C-POC_GPIO_6)") (pintype "passive"))
    (pad "2" smd roundrect (at 0.48 0 90) (size 0.59 0.64) (layers "B.Cu" "B.Paste" "B.Mask") (roundrect_rratio 0.25)
      (net 1 "GND") (pintype "passive"))
  )
	(footprint "antmicro-footprints:C_0402_1005Metric" (layer "B.Cu")
    (at 155.085 78.42 180)
    (descr "Capacitor SMD 0402")
    (tags "capacitor SMD 0402")
    (property "Author" "Antmicro")
    (property "Dielectric" "")
    (property "License" "Apache-2.0")
    (property "MPN" "CC0402KRX5R6BB224")
    (property "Manufacturer" "YAGEO")
    (property "Sheetfile" "tb.kicad_sch")
    (property "Sheetname" "TB Controller")
    (property "Val" "220n")
    (property "Voltage" "")
    (property "ki_description" "SMD Multilayer Ceramic Capacitor, 0.22 µF, 10 V, 0402 [1005 Metric], ± 10%, X5R, CC Series")
    (property "ki_keywords" "0402, SMT, CAPACITOR, PASSIVE, MLCC, CERAMIC")
    (attr smd)
    (fp_text reference "C103" (at 1.034 -0.431) (layer "B.SilkS")
        (effects (font (size 0.7 0.7) (thickness 0.15)) (justify left bottom mirror))
    )
    (fp_text value "C_220n_0402" (at -1.022927 -2.155213) (layer "B.Fab")
        (effects (font (size 0.7 0.7) (thickness 0.15)) (justify left bottom mirror))
    )
    (fp_text user "License: Apache-2.0" (at -0.939 -5.799) (layer "B.Fab") hide
        (effects (font (size 0.7 0.7) (thickness 0.15)) (justify left bottom mirror))
    )
    (fp_text user "Author: Antmicro" (at -0.939 -3.399) (layer "B.Fab") hide
        (effects (font (size 0.7 0.7) (thickness 0.15)) (justify left bottom mirror))
    )
    (fp_text user "${REFERENCE}" (at -0.939 -4.599) (layer "B.Fab") hide
        (effects (font (size 0.7 0.7) (thickness 0.15)) (justify left bottom mirror))
    )
    (fp_rect (start -0.925 0.47) (end 0.925 -0.47)
      (stroke (width 0.05) (type default)) (fill none) (layer "B.CrtYd"))
    (fp_line (start -0.494 -0.248) (end -0.494 0.25)
      (stroke (width 0.15) (type solid)) (layer "B.Fab"))
    (fp_line (start -0.494 0.25) (end 0.504 0.25)
      (stroke (width 0.15) (type solid)) (layer "B.Fab"))
    (fp_line (start 0.504 -0.248) (end -0.494 -0.248)
      (stroke (width 0.15) (type solid)) (layer "B.Fab"))
    (fp_line (start 0.504 0.25) (end 0.504 -0.248)
      (stroke (width 0.15) (type solid)) (layer "B.Fab"))
    (pad "1" smd roundrect (at -0.48 0 180) (size 0.59 0.64) (layers "B.Cu" "B.Paste" "B.Mask") (roundrect_rratio 0.25)
      (net 21 "TB_TX1_N") (pintype "passive"))
    (pad "2" smd roundrect (at 0.48 0 180) (size 0.59 0.64) (layers "B.Cu" "B.Paste" "B.Mask") (roundrect_rratio 0.25)
      (net 22 "/TB Controller/PA_TX1_N") (pintype "passive"))
  )
	(footprint "antmicro-footprints:C_0402_1005Metric" (layer "B.Cu")
    (at 132.85 78.875)
    (descr "Capacitor SMD 0402")
    (tags "capacitor SMD 0402")
    (property "Author" "Antmicro")
    (property "Dielectric" "")
    (property "License" "Apache-2.0")
    (property "MPN" "C1005X6S1A105K050BC")
    (property "Manufacturer" "TDK")
    (property "Sheetfile" "tb-power.kicad_sch")
    (property "Sheetname" "Thunderbolt Controller - Power")
    (property "Val" "1u")
    (property "Voltage" "")
    (property "ki_description" "SMD Multilayer Ceramic Capacitor, 1 µF, 10 V, 0402 [1005 Metric], ± 10%, X6S, C")
    (property "ki_keywords" "0402, SMT, CAPACITOR, PASSIVE, CERAMIC, MLCC")
    (attr smd)
    (fp_text reference "C57" (at 17.518 7.612 180) (layer "B.SilkS")
        (effects (font (size 0.7 0.7) (thickness 0.15)) (justify left bottom mirror))
    )
    (fp_text value "C_1u_0402" (at -1.022927 -2.155213 180) (layer "B.Fab")
        (effects (font (size 0.7 0.7) (thickness 0.15)) (justify left bottom mirror))
    )
    (fp_text user "${REFERENCE}" (at -0.939 -4.599 180) (layer "B.Fab") hide
        (effects (font (size 0.7 0.7) (thickness 0.15)) (justify left bottom mirror))
    )
    (fp_text user "Author: Antmicro" (at -0.939 -3.399 180) (layer "B.Fab") hide
        (effects (font (size 0.7 0.7) (thickness 0.15)) (justify left bottom mirror))
    )
    (fp_text user "License: Apache-2.0" (at -0.939 -5.799 180) (layer "B.Fab") hide
        (effects (font (size 0.7 0.7) (thickness 0.15)) (justify left bottom mirror))
    )
    (fp_rect (start -0.925 0.47) (end 0.925 -0.47)
      (stroke (width 0.05) (type default)) (fill none) (layer "B.CrtYd"))
    (fp_line (start -0.494 -0.248) (end -0.494 0.25)
      (stroke (width 0.15) (type solid)) (layer "B.Fab"))
    (fp_line (start -0.494 0.25) (end 0.504 0.25)
      (stroke (width 0.15) (type solid)) (layer "B.Fab"))
    (fp_line (start 0.504 -0.248) (end -0.494 -0.248)
      (stroke (width 0.15) (type solid)) (layer "B.Fab"))
    (fp_line (start 0.504 0.25) (end 0.504 -0.248)
      (stroke (width 0.15) (type solid)) (layer "B.Fab"))
    (pad "1" smd roundrect (at -0.48 0) (size 0.59 0.64) (layers "B.Cu" "B.Paste" "B.Mask") (roundrect_rratio 0.25)
      (net 1 "GND") (pintype "passive"))
    (pad "2" smd roundrect (at 0.48 0) (size 0.59 0.64) (layers "B.Cu" "B.Paste" "B.Mask") (roundrect_rratio 0.25)
      (net 107 "Net-(C54-Pad2)") (pintype "passive"))
  )
	(footprint "antmicro-footprints:R_0402_1005Metric" (layer "B.Cu")
    (at 113.125 86.17 90)
    (descr "Resistor SMD 0402")
    (tags "resistor SMD 0402")
    (property "Author" "Antmicro")
    (property "License" "Apache-2.0")
    (property "MPN" "CR0402-FX-1002GLF")
    (property "Manufacturer" "Bourns")
    (property "Sheetfile" "power.kicad_sch")
    (property "Sheetname" "Power")
    (property "Tolerance" "1%")
    (property "Val" "10k")
    (property "ki_description" "SMD Chip Resistor, 10 kohm, ± 1%, 62.5 mW, 0402 [1005 Metric], Thick Film, General Purpose")
    (property "ki_keywords" "0402, SMT, RESISTOR, PASSIVE")
    (attr smd)
    (fp_text reference "R44" (at -0.825 0.413 270) (layer "B.SilkS")
        (effects (font (size 0.7 0.7) (thickness 0.15)) (justify left bottom mirror))
    )
    (fp_text value "R_10k_0402" (at -1.011843 -1.772047 270) (layer "B.Fab")
        (effects (font (size 0.7 0.7) (thickness 0.15)) (justify left bottom mirror))
    )
    (fp_text user "${REFERENCE}" (at -0.95 -3.168 270) (layer "B.Fab") hide
        (effects (font (size 0.7 0.7) (thickness 0.15)) (justify left bottom mirror))
    )
    (fp_text user "License: Apache-2.0" (at -0.95 -5.169 270) (layer "B.Fab") hide
        (effects (font (size 0.7 0.7) (thickness 0.15)) (justify left bottom mirror))
    )
    (fp_text user "Author: Antmicro" (at -0.95 -4.169 270) (layer "B.Fab") hide
        (effects (font (size 0.7 0.7) (thickness 0.15)) (justify left bottom mirror))
    )
    (fp_rect (start -0.925 0.47) (end 0.925 -0.47)
      (stroke (width 0.05) (type default)) (fill none) (layer "B.CrtYd"))
    (fp_rect (start -0.5 0.25) (end 0.5 -0.25)
      (stroke (width 0.15) (type solid)) (fill none) (layer "B.Fab"))
    (pad "1" smd roundrect (at -0.48 0 90) (size 0.59 0.64) (layers "B.Cu" "B.Paste" "B.Mask") (roundrect_rratio 0.25)
      (net 1 "GND") (pintype "passive"))
    (pad "2" smd roundrect (at 0.48 0 90) (size 0.59 0.64) (layers "B.Cu" "B.Paste" "B.Mask") (roundrect_rratio 0.25)
      (net 169 "Net-(U1-FB)") (pintype "passive"))
  )
	(footprint "antmicro-footprints:C_0402_1005Metric" (layer "B.Cu")
    (at 137.725 82.725 180)
    (descr "Capacitor SMD 0402")
    (tags "capacitor SMD 0402")
    (property "Author" "Antmicro")
    (property "Dielectric" "")
    (property "License" "Apache-2.0")
    (property "MPN" "C1005X6S1A105K050BC")
    (property "Manufacturer" "TDK")
    (property "Sheetfile" "tb-power.kicad_sch")
    (property "Sheetname" "Thunderbolt Controller - Power")
    (property "Val" "1u")
    (property "Voltage" "")
    (property "ki_description" "SMD Multilayer Ceramic Capacitor, 1 µF, 10 V, 0402 [1005 Metric], ± 10%, X6S, C")
    (property "ki_keywords" "0402, SMT, CAPACITOR, PASSIVE, CERAMIC, MLCC")
    (attr smd)
    (fp_text reference "C90" (at -17.596 -8.334) (layer "B.SilkS")
        (effects (font (size 0.7 0.7) (thickness 0.15)) (justify left bottom mirror))
    )
    (fp_text value "C_1u_0402" (at -1.022927 -2.155213) (layer "B.Fab")
        (effects (font (size 0.7 0.7) (thickness 0.15)) (justify left bottom mirror))
    )
    (fp_text user "Author: Antmicro" (at -0.939 -3.399) (layer "B.Fab") hide
        (effects (font (size 0.7 0.7) (thickness 0.15)) (justify left bottom mirror))
    )
    (fp_text user "License: Apache-2.0" (at -0.939 -5.799) (layer "B.Fab") hide
        (effects (font (size 0.7 0.7) (thickness 0.15)) (justify left bottom mirror))
    )
    (fp_text user "${REFERENCE}" (at -0.939 -4.599) (layer "B.Fab") hide
        (effects (font (size 0.7 0.7) (thickness 0.15)) (justify left bottom mirror))
    )
    (fp_rect (start -0.925 0.47) (end 0.925 -0.47)
      (stroke (width 0.05) (type default)) (fill none) (layer "B.CrtYd"))
    (fp_line (start -0.494 -0.248) (end -0.494 0.25)
      (stroke (width 0.15) (type solid)) (layer "B.Fab"))
    (fp_line (start -0.494 0.25) (end 0.504 0.25)
      (stroke (width 0.15) (type solid)) (layer "B.Fab"))
    (fp_line (start 0.504 -0.248) (end -0.494 -0.248)
      (stroke (width 0.15) (type solid)) (layer "B.Fab"))
    (fp_line (start 0.504 0.25) (end 0.504 -0.248)
      (stroke (width 0.15) (type solid)) (layer "B.Fab"))
    (pad "1" smd roundrect (at -0.48 0 180) (size 0.59 0.64) (layers "B.Cu" "B.Paste" "B.Mask") (roundrect_rratio 0.25)
      (net 1 "GND") (pintype "passive"))
    (pad "2" smd roundrect (at 0.48 0 180) (size 0.59 0.64) (layers "B.Cu" "B.Paste" "B.Mask") (roundrect_rratio 0.25)
      (net 113 "Net-(U4A-VCC0P9_LVR_SENSE)") (pintype "passive"))
  )
	(footprint "antmicro-footprints:C_0402_1005Metric" (layer "B.Cu")
    (at 132.5 92.65 -90)
    (descr "Capacitor SMD 0402")
    (tags "capacitor SMD 0402")
    (property "Author" "Antmicro")
    (property "Dielectric" "")
    (property "License" "Apache-2.0")
    (property "MPN" "CC0402KRX5R6BB224")
    (property "Manufacturer" "YAGEO")
    (property "Sheetfile" "tb.kicad_sch")
    (property "Sheetname" "TB Controller")
    (property "Val" "220n")
    (property "Voltage" "")
    (property "ki_description" "SMD Multilayer Ceramic Capacitor, 0.22 µF, 10 V, 0402 [1005 Metric], ± 10%, X5R, CC Series")
    (property "ki_keywords" "0402, SMT, CAPACITOR, PASSIVE, MLCC, CERAMIC")
    (attr smd)
    (fp_text reference "C106" (at -3.877 -0.47 90) (layer "B.SilkS")
        (effects (font (size 0.7 0.7) (thickness 0.15)) (justify left bottom mirror))
    )
    (fp_text value "C_220n_0402" (at -1.022927 -2.155213 90) (layer "B.Fab")
        (effects (font (size 0.7 0.7) (thickness 0.15)) (justify left bottom mirror))
    )
    (fp_text user "License: Apache-2.0" (at -0.939 -5.799 90) (layer "B.Fab") hide
        (effects (font (size 0.7 0.7) (thickness 0.15)) (justify left bottom mirror))
    )
    (fp_text user "${REFERENCE}" (at -0.939 -4.599 90) (layer "B.Fab") hide
        (effects (font (size 0.7 0.7) (thickness 0.15)) (justify left bottom mirror))
    )
    (fp_text user "Author: Antmicro" (at -0.939 -3.399 90) (layer "B.Fab") hide
        (effects (font (size 0.7 0.7) (thickness 0.15)) (justify left bottom mirror))
    )
    (fp_rect (start -0.925 0.47) (end 0.925 -0.47)
      (stroke (width 0.05) (type default)) (fill none) (layer "B.CrtYd"))
    (fp_line (start -0.494 -0.248) (end -0.494 0.25)
      (stroke (width 0.15) (type solid)) (layer "B.Fab"))
    (fp_line (start -0.494 0.25) (end 0.504 0.25)
      (stroke (width 0.15) (type solid)) (layer "B.Fab"))
    (fp_line (start 0.504 -0.248) (end -0.494 -0.248)
      (stroke (width 0.15) (type solid)) (layer "B.Fab"))
    (fp_line (start 0.504 0.25) (end 0.504 -0.248)
      (stroke (width 0.15) (type solid)) (layer "B.Fab"))
    (pad "1" smd roundrect (at -0.48 0 270) (size 0.59 0.64) (layers "B.Cu" "B.Paste" "B.Mask") (roundrect_rratio 0.25)
      (net 77 "/TB Controller/TX1_N") (pintype "passive"))
    (pad "2" smd roundrect (at 0.48 0 270) (size 0.59 0.64) (layers "B.Cu" "B.Paste" "B.Mask") (roundrect_rratio 0.25)
      (net 25 "PCIE_TX1_N") (pintype "passive"))
  )
	(footprint "antmicro-footprints:C_0402_1005Metric" (layer "B.Cu")
    (at 127.5 92.65 -90)
    (descr "Capacitor SMD 0402")
    (tags "capacitor SMD 0402")
    (property "Author" "Antmicro")
    (property "Dielectric" "")
    (property "License" "Apache-2.0")
    (property "MPN" "CC0402KRX5R6BB224")
    (property "Manufacturer" "YAGEO")
    (property "Sheetfile" "tb.kicad_sch")
    (property "Sheetname" "TB Controller")
    (property "Val" "220n")
    (property "Voltage" "")
    (property "ki_description" "SMD Multilayer Ceramic Capacitor, 0.22 µF, 10 V, 0402 [1005 Metric], ± 10%, X5R, CC Series")
    (property "ki_keywords" "0402, SMT, CAPACITOR, PASSIVE, MLCC, CERAMIC")
    (attr smd)
    (fp_text reference "C105" (at -3.877 -0.47 90) (layer "B.SilkS")
        (effects (font (size 0.7 0.7) (thickness 0.15)) (justify left bottom mirror))
    )
    (fp_text value "C_220n_0402" (at -1.022927 -2.155213 90) (layer "B.Fab")
        (effects (font (size 0.7 0.7) (thickness 0.15)) (justify left bottom mirror))
    )
    (fp_text user "License: Apache-2.0" (at -0.939 -5.799 90) (layer "B.Fab") hide
        (effects (font (size 0.7 0.7) (thickness 0.15)) (justify left bottom mirror))
    )
    (fp_text user "Author: Antmicro" (at -0.939 -3.399 90) (layer "B.Fab") hide
        (effects (font (size 0.7 0.7) (thickness 0.15)) (justify left bottom mirror))
    )
    (fp_text user "${REFERENCE}" (at -0.939 -4.599 90) (layer "B.Fab") hide
        (effects (font (size 0.7 0.7) (thickness 0.15)) (justify left bottom mirror))
    )
    (fp_rect (start -0.925 0.47) (end 0.925 -0.47)
      (stroke (width 0.05) (type default)) (fill none) (layer "B.CrtYd"))
    (fp_line (start -0.494 -0.248) (end -0.494 0.25)
      (stroke (width 0.15) (type solid)) (layer "B.Fab"))
    (fp_line (start -0.494 0.25) (end 0.504 0.25)
      (stroke (width 0.15) (type solid)) (layer "B.Fab"))
    (fp_line (start 0.504 -0.248) (end -0.494 -0.248)
      (stroke (width 0.15) (type solid)) (layer "B.Fab"))
    (fp_line (start 0.504 0.25) (end 0.504 -0.248)
      (stroke (width 0.15) (type solid)) (layer "B.Fab"))
    (pad "1" smd roundrect (at -0.48 0 270) (size 0.59 0.64) (layers "B.Cu" "B.Paste" "B.Mask") (roundrect_rratio 0.25)
      (net 76 "/TB Controller/TX0_N") (pintype "passive"))
    (pad "2" smd roundrect (at 0.48 0 270) (size 0.59 0.64) (layers "B.Cu" "B.Paste" "B.Mask") (roundrect_rratio 0.25)
      (net 24 "PCIE_TX0_N") (pintype "passive"))
  )
)
